# S9S_MB_2U (Grand Teton) — schematic netlist excerpt (pin names and nets, part order shuffled) for the footprints in the layout excerpt that follows; sources: Cadence DE-HDL packaged netlist, KiCad conversion of 03242023_DA0F0TMBIJ0_F0T_Motherboard_J_brd_V01_OCP.brd

R1504  Q_RES  33.2 1% CHIP  pkg 0402LF  page 155 : A = RST_OCP_V3_1_BUF_N ; B = RST_PERST2_OCP_SFF_N

X37  TP_TDR_4P_FTS  TP_TDR_4P_DIP EMPTY  pkg TH  page 310
  S1  = UNNAMED_310_TPTDR4PFTS_I7_S1
  P1  = T1_GND
  P2  = T1_GND
  S2  = UNNAMED_310_TPTDR4PFTS_I7_S2

(kicad_pcb
	(version 20260206)
	(generator "pcbnew")
	(generator_version "10.0")
	(general
		(thickness 1.6)
		(legacy_teardrops no)
	)
	(paper "A4")
	(title_block
		(title "03242023_DA0F0TMBIJ0_F0T_Motherboard_J_brd_V01_OCP.brd")
		(comment 1 "Grand Teton / footprints 4761-4762 of 6105")
	)
	(layers
		(0 "F.Cu" signal "TOP")
		(4 "In1.Cu" signal "GND")
		(6 "In2.Cu" signal "IN1")
		(8 "In3.Cu" signal "GND1")
		(10 "In4.Cu" signal "IN2")
		(12 "In5.Cu" signal "GND2")
		(14 "In6.Cu" signal "IN3")
		(16 "In7.Cu" signal "GND3")
		(18 "In8.Cu" signal "VCC")
		(20 "In9.Cu" signal "VCC1")
		(22 "In10.Cu" signal "GND4")
		(24 "In11.Cu" signal "IN4")
		(26 "In12.Cu" signal "GND5")
		(28 "In13.Cu" signal "IN5")
		(30 "In14.Cu" signal "GND6")
		(32 "In15.Cu" signal "IN6")
		(34 "In16.Cu" signal "GND7")
		(2 "B.Cu" signal "BOTTOM")
		(9 "F.Adhes" user "F.Adhesive")
		(11 "B.Adhes" user "B.Adhesive")
		(13 "F.Paste" user "Package Geometry/Pastemask Top")
		(15 "B.Paste" user "Package Geometry/Pastemask Bottom")
		(5 "F.SilkS" user "Ref Des/Silkscreen Top")
		(7 "B.SilkS" user "Ref Des/Silkscreen Bottom")
		(1 "F.Mask" user "Board Geometry/Soldermask Top")
		(3 "B.Mask" user "Board Geometry/Soldermask Bottom")
		(17 "Dwgs.User" user "User.Drawings")
		(19 "Cmts.User" user "User.Comments")
		(21 "Eco1.User" user "User.Eco1")
		(23 "Eco2.User" user "User.Eco2")
		(25 "Edge.Cuts" user "Board Geometry/Outline")
		(27 "Margin" user)
		(31 "F.CrtYd" user "Package Geometry/Place Bound Top")
		(29 "B.CrtYd" user "Package Geometry/Place Bound Bottom")
		(35 "F.Fab" user "Ref Des/Assembly Top")
		(33 "B.Fab" user "Ref Des/Assembly Bottom")
	)
	(footprint ""
		(layer "B.Cu")
		(at 485.20985 -211.012532 -90)
		(property "Reference" "X37"
			(at -0.442468 -2.18948 270)
			(unlocked yes)
			(layer "B.SilkS")
			(effects
				(font
					(size 0.7874 0.5842)
					(thickness 0.1524)
				)
				(justify left mirror)
			)
		)
		(property "Value" ""
			(at 0 0 90)
			(layer "B.Fab")
			(effects
				(font
					(size 1.27 1.27)
				)
				(justify mirror)
			)
		)
		(property "Device Type" "TP_TDR_4P_FTS_TH-TP_TDR_4P_DIPA"
			(at -1.30175 1.27 180)
			(unlocked yes)
			(layer "B.Fab")
			(hide yes)
			(effects
				(font
					(size 0.635 0.4064)
					(thickness 0.1524)
				)
				(justify mirror)
			)
		)
		(property "User Part Number" "N_A"
			(at -1.30175 1.27 180)
			(unlocked yes)
			(layer "Cmts.User")
			(hide yes)
			(effects
				(font
					(size 0.635 0.4064)
					(thickness 0.1524)
				)
				(justify mirror)
			)
		)
		(duplicate_pad_numbers_are_jumpers no)
		(fp_line
			(start -2.54 3.81)
			(end -2.54 3.6703)
			(stroke
				(width 0.1524)
				(type default)
			)
			(layer "B.SilkS")
		)
		(fp_line
			(start 0 3.81)
			(end -2.54 3.81)
			(stroke
				(width 0.1524)
				(type default)
			)
			(layer "B.SilkS")
		)
		(fp_line
			(start 0 3.175)
			(end 0 3.81)
			(stroke
				(width 0.1524)
				(type default)
			)
			(layer "B.SilkS")
		)
		(fp_line
			(start -2.54 1.4097)
			(end -2.54 1.1303)
			(stroke
				(width 0.1524)
				(type default)
			)
			(layer "B.SilkS")
		)
		(fp_line
			(start 0 0.635)
			(end 0 1.905)
			(stroke
				(width 0.1524)
				(type default)
			)
			(layer "B.SilkS")
		)
		(fp_line
			(start -2.54 -1.1303)
			(end -2.54 -1.27)
			(stroke
				(width 0.1524)
				(type default)
			)
			(layer "B.SilkS")
		)
		(fp_line
			(start -2.54 -1.27)
			(end 0 -1.27)
			(stroke
				(width 0.1524)
				(type default)
			)
			(layer "B.SilkS")
		)
		(fp_line
			(start 0 -1.27)
			(end 0 -0.635)
			(stroke
				(width 0.1524)
				(type default)
			)
			(layer "B.SilkS")
		)
		(fp_poly
			(pts
				(xy 0.761746 0) (xy 2.285746 -0.762) (xy 2.285746 0.762)
			)
			(stroke
				(width 0)
				(type default)
			)
			(fill yes)
			(layer "B.SilkS")
		)
		(fp_line
			(start -2.54 3.81)
			(end -2.54 -1.27)
			(stroke
				(width 0.1)
				(type default)
			)
			(layer "B.Fab")
		)
		(fp_line
			(start 0 3.81)
			(end -2.54 3.81)
			(stroke
				(width 0.1)
				(type default)
			)
			(layer "B.Fab")
		)
		(fp_line
			(start -2.54 -1.27)
			(end 0 -1.27)
			(stroke
				(width 0.1)
				(type default)
			)
			(layer "B.Fab")
		)
		(fp_line
			(start 0 -1.27)
			(end 0 3.81)
			(stroke
				(width 0.1)
				(type default)
			)
			(layer "B.Fab")
		)
		(fp_poly
			(pts
				(xy 0.761746 0) (xy 2.285746 -0.762) (xy 2.285746 0.762)
			)
			(stroke
				(width 0)
				(type default)
			)
			(fill yes)
			(layer "B.Fab")
		)
		(pad "1" thru_hole circle
			(at 0 0 90)
			(size 1.0033 1.0033)
			(drill 0.249936)
			(layers "*.Cu" "*.Mask")
			(remove_unused_layers no)
			(net "TDR_DIFF_85_NECK_IN4_DP")
			(clearance 0.10795)
			(padstack
				(mode front_inner_back)
				(layer "Inner"
					(shape circle)
					(size 0.8001 0.8001)
					(clearance 0.1524)
				)
				(layer "B.Cu"
					(shape circle)
					(size 1.0033 1.0033)
					(thermal_gap 0.10795)
					(clearance 0.10795)
				)
			)
		)
		(pad "2" thru_hole circle
			(at -2.54 0 90)
			(size 1.9939 1.9939)
			(drill 0.249936)
			(layers "*.Cu" "*.Mask")
			(remove_unused_layers no)
			(net "T1_GND")
			(clearance 0.10795)
			(padstack
				(mode front_inner_back)
				(layer "Inner"
					(shape circle)
					(size 0.8001 0.8001)
					(clearance 0.1524)
				)
				(layer "B.Cu"
					(shape circle)
					(size 1.9939 1.9939)
					(thermal_gap 0.10795)
					(clearance 0.10795)
				)
			)
		)
		(pad "3" thru_hole circle
			(at -2.54 2.54 90)
			(size 1.9939 1.9939)
			(drill 0.249936)
			(layers "*.Cu" "*.Mask")
			(remove_unused_layers no)
			(net "T1_GND")
			(clearance 0.10795)
			(padstack
				(mode front_inner_back)
				(layer "Inner"
					(shape circle)
					(size 0.8001 0.8001)
					(clearance 0.1524)
				)
				(layer "B.Cu"
					(shape circle)
					(size 1.9939 1.9939)
					(thermal_gap 0.10795)
					(clearance 0.10795)
				)
			)
		)
		(pad "4" thru_hole circle
			(at 0 2.54 90)
			(size 1.0033 1.0033)
			(drill 0.249936)
			(layers "*.Cu" "*.Mask")
			(remove_unused_layers no)
			(net "TDR_DIFF_85_NECK_IN4_DN")
			(clearance 0.10795)
			(padstack
				(mode front_inner_back)
				(layer "Inner"
					(shape circle)
					(size 0.8001 0.8001)
					(clearance 0.1524)
				)
				(layer "B.Cu"
					(shape circle)
					(size 1.0033 1.0033)
					(thermal_gap 0.10795)
					(clearance 0.10795)
				)
			)
		)
	)
	(footprint ""
		(layer "B.Cu")
		(at 452.01205 -3.866388 -90)
		(property "Reference" "R1504"
			(at 0 0 90)
			(layer "B.SilkS")
			(hide yes)
			(effects
				(font
					(size 1.27 1.27)
				)
				(justify mirror)
			)
		)
		(property "Value" ""
			(at 0 0 90)
			(layer "B.Fab")
			(effects
				(font
					(size 1.27 1.27)
				)
				(justify mirror)
			)
		)
		(duplicate_pad_numbers_are_jumpers no)
		(fp_line
			(start -0.7874 0.4064)
			(end 0.7874 0.4064)
			(stroke
				(width 0.1524)
				(type default)
			)
			(layer "B.SilkS")
		)
		(fp_line
			(start 0.7874 0.4064)
			(end 0.7874 -0.4064)
			(stroke
				(width 0.1524)
				(type default)
			)
			(layer "B.SilkS")
		)
		(fp_line
			(start -0.7874 -0.4064)
			(end -0.7874 0.4064)
			(stroke
				(width 0.1524)
				(type default)
			)
			(layer "B.SilkS")
		)
		(fp_line
			(start 0.7874 -0.4064)
			(end -0.7874 -0.4064)
			(stroke
				(width 0.1524)
				(type default)
			)
			(layer "B.SilkS")
		)
		(fp_line
			(start -0.67945 0.3048)
			(end -0.120396 0.3048)
			(stroke
				(width 0.1)
				(type default)
			)
			(layer "B.Fab")
		)
		(fp_line
			(start -0.120396 0.3048)
			(end -0.120396 0.2794)
			(stroke
				(width 0.1)
				(type default)
			)
			(layer "B.Fab")
		)
		(fp_line
			(start 0.12065 0.3048)
			(end 0.67945 0.3048)
			(stroke
				(width 0.1)
				(type default)
			)
			(layer "B.Fab")
		)
		(fp_line
			(start 0.67945 0.3048)
			(end 0.67945 -0.305054)
			(stroke
				(width 0.1)
				(type default)
			)
			(layer "B.Fab")
		)
		(fp_line
			(start -0.120396 0.2794)
			(end 0.12065 0.2794)
			(stroke
				(width 0.1)
				(type default)
			)
			(layer "B.Fab")
		)
		(fp_line
			(start 0.12065 0.2794)
			(end 0.12065 0.3048)
			(stroke
				(width 0.1)
				(type default)
			)
			(layer "B.Fab")
		)
		(fp_line
			(start -0.12065 -0.2794)
			(end -0.12065 -0.3048)
			(stroke
				(width 0.1)
				(type default)
			)
			(layer "B.Fab")
		)
		(fp_line
			(start 0.12065 -0.2794)
			(end -0.12065 -0.2794)
			(stroke
				(width 0.1)
				(type default)
			)
			(layer "B.Fab")
		)
		(fp_line
			(start -0.67945 -0.3048)
			(end -0.67945 0.3048)
			(stroke
				(width 0.1)
				(type default)
			)
			(layer "B.Fab")
		)
		(fp_line
			(start -0.12065 -0.3048)
			(end -0.67945 -0.3048)
			(stroke
				(width 0.1)
				(type default)
			)
			(layer "B.Fab")
		)
		(fp_line
			(start 0.12065 -0.305054)
			(end 0.12065 -0.2794)
			(stroke
				(width 0.1)
				(type default)
			)
			(layer "B.Fab")
		)
		(fp_line
			(start 0.67945 -0.305054)
			(end 0.12065 -0.305054)
			(stroke
				(width 0.1)
				(type default)
			)
			(layer "B.Fab")
		)
		(pad "1" smd circle
			(at 0.40005 0 90)
			(size 0 0)
			(layers "B.Cu" "B.Mask" "B.Paste")
			(net "RST_OCP_V3_1_BUF_N")
		)
		(pad "2" smd circle
			(at -0.40005 0 90)
			(size 0 0)
			(layers "B.Cu" "B.Mask" "B.Paste")
			(net "RST_PERST2_OCP_SFF_N")
		)
	)
)
